(kicad_pcb
	(version 20260206)
	(generator "pcbnew")
	(generator_version "10.0")
	(general
		(thickness 1.6)
		(legacy_teardrops no)
	)
	(paper "A4")
	(title_block
		(title "12092022_DA0F0TMDCD0_F0T_Management_Board_D_brd_V3_OCP.brd")
		(comment 1 "Grand Teton / footprints 1302-1307 of 1440")
	)
	(layers
		(0 "F.Cu" signal "TOP")
		(4 "In1.Cu" signal "GND")
		(6 "In2.Cu" signal "IN1")
		(8 "In3.Cu" signal "GND1")
		(10 "In4.Cu" signal "IN2")
		(12 "In5.Cu" signal "VCC")
		(14 "In6.Cu" signal "VCC1")
		(16 "In7.Cu" signal "IN3")
		(18 "In8.Cu" signal "GND2")
		(20 "In9.Cu" signal "IN4")
		(22 "In10.Cu" signal "GND3")
		(2 "B.Cu" signal "BOTTOM")
		(9 "F.Adhes" user "F.Adhesive")
		(11 "B.Adhes" user "B.Adhesive")
		(13 "F.Paste" user "Package Geometry/Pastemask Top")
		(15 "B.Paste" user "Package Geometry/Pastemask Bottom")
		(5 "F.SilkS" user "Ref Des/Silkscreen Top")
		(7 "B.SilkS" user "Ref Des/Silkscreen Bottom")
		(1 "F.Mask" user "Board Geometry/Soldermask Top")
		(3 "B.Mask" user "Board Geometry/Soldermask Bottom")
		(17 "Dwgs.User" user "User.Drawings")
		(19 "Cmts.User" user "User.Comments")
		(21 "Eco1.User" user "User.Eco1")
		(23 "Eco2.User" user "User.Eco2")
		(25 "Edge.Cuts" user "Board Geometry/Outline")
		(27 "Margin" user)
		(31 "F.CrtYd" user "Package Geometry/Place Bound Top")
		(29 "B.CrtYd" user "Package Geometry/Place Bound Bottom")
		(35 "F.Fab" user "Ref Des/Assembly Top")
		(33 "B.Fab" user "Ref Des/Assembly Bottom")
	)
	(footprint ""
		(layer "B.Cu")
		(at 101.2825 18.001488 -90)
		(property "Reference" "J27"
			(at 1.048512 2.88417 270)
			(unlocked yes)
			(layer "B.SilkS")
			(effects
				(font
					(size 0.7874 0.5842)
					(thickness 0.1524)
				)
				(justify left mirror)
			)
		)
		(property "Value" ""
			(at 0 0 90)
			(layer "B.Fab")
			(effects
				(font
					(size 1.27 1.27)
				)
				(justify mirror)
			)
		)
		(duplicate_pad_numbers_are_jumpers no)
		(fp_line
			(start -1.2192 2.1082)
			(end 1.2192 2.1082)
			(stroke
				(width 0.1524)
				(type default)
			)
			(layer "B.SilkS")
		)
		(fp_line
			(start 1.2192 2.1082)
			(end 1.2192 -2.1082)
			(stroke
				(width 0.1524)
				(type default)
			)
			(layer "B.SilkS")
		)
		(fp_line
			(start -1.2192 0.465582)
			(end -1.2192 2.1082)
			(stroke
				(width 0.1524)
				(type default)
			)
			(layer "B.SilkS")
		)
		(fp_line
			(start -1.2192 -2.1082)
			(end -1.2192 -0.45085)
			(stroke
				(width 0.1524)
				(type default)
			)
			(layer "B.SilkS")
		)
		(fp_line
			(start 1.2192 -2.1082)
			(end -1.2192 -2.1082)
			(stroke
				(width 0.1524)
				(type default)
			)
			(layer "B.SilkS")
		)
		(pad "" np_thru_hole circle
			(at -3.4671 -1.27 180)
			(size 1.0414 1.0414)
			(drill 1.0414)
			(layers "*.Cu" "*.Mask")
			(clearance 0.381)
			(thermal_gap 0.381)
		)
		(pad "" np_thru_hole circle
			(at -3.4671 1.27 180)
			(size 1.0414 1.0414)
			(drill 1.0414)
			(layers "*.Cu" "*.Mask")
			(clearance 0.381)
			(thermal_gap 0.381)
		)
		(pad "" np_thru_hole circle
			(at 2.8829 -1.27 180)
			(size 1.0414 1.0414)
			(drill 1.0414)
			(layers "*.Cu" "*.Mask")
			(clearance 0.381)
			(thermal_gap 0.381)
		)
		(pad "" np_thru_hole circle
			(at 2.8829 1.27 180)
			(size 1.0414 1.0414)
			(drill 1.0414)
			(layers "*.Cu" "*.Mask")
			(clearance 0.381)
			(thermal_gap 0.381)
		)
		(pad "1" smd rect
			(at -0.8255 -0.249936 180)
			(size 0.3048 0.508)
			(layers "B.Cu" "B.Mask" "B.Paste")
			(net "85_10INCH_BOT_DN")
		)
		(pad "2" smd rect
			(at -0.8255 0.249936 180)
			(size 0.3048 0.508)
			(layers "B.Cu" "B.Mask" "B.Paste")
			(net "85_10INCH_BOT_DP")
		)
		(pad "3" smd circle
			(at 0 0 90)
			(size 0 0)
			(layers "B.Cu" "B.Mask" "B.Paste")
			(net "GND_P1")
		)
		(zone
			(layers "F.Cu" "B.Cu" "In1.Cu" "In2.Cu" "In3.Cu" "In4.Cu" "In5.Cu" "In6.Cu"
				"In7.Cu" "In8.Cu" "In9.Cu" "In10.Cu"
			)
			(hatch none 0.5)
			(connect_pads
				(clearance 0)
			)
			(min_thickness 0.25)
			(keepout
				(tracks not_allowed)
				(vias allowed)
				(pads allowed)
				(copperpour not_allowed)
				(footprints allowed)
			)
			(placement
				(enabled no)
				(sheetname "")
			)
			(fill
				(thermal_gap 0.5)
				(thermal_bridge_width 0.5)
				(island_removal_mode 0)
			)
			(polygon
				(pts
					(arc
						(start 100.9396 14.534388)
						(mid 99.0854 14.534388)
						(end 100.9396 14.534388)
					)
				)
			)
		)
		(zone
			(layers "F.Cu" "B.Cu" "In1.Cu" "In2.Cu" "In3.Cu" "In4.Cu" "In5.Cu" "In6.Cu"
				"In7.Cu" "In8.Cu" "In9.Cu" "In10.Cu"
			)
			(hatch none 0.5)
			(connect_pads
				(clearance 0)
			)
			(min_thickness 0.25)
			(keepout
				(tracks not_allowed)
				(vias allowed)
				(pads allowed)
				(copperpour not_allowed)
				(footprints allowed)
			)
			(placement
				(enabled no)
				(sheetname "")
			)
			(fill
				(thermal_gap 0.5)
				(thermal_bridge_width 0.5)
				(island_removal_mode 0)
			)
			(polygon
				(pts
					(arc
						(start 100.9396 20.884388)
						(mid 99.0854 20.884388)
						(end 100.9396 20.884388)
					)
				)
			)
		)
		(zone
			(layers "F.Cu" "B.Cu" "In1.Cu" "In2.Cu" "In3.Cu" "In4.Cu" "In5.Cu" "In6.Cu"
				"In7.Cu" "In8.Cu" "In9.Cu" "In10.Cu"
			)
			(hatch none 0.5)
			(connect_pads
				(clearance 0)
			)
			(min_thickness 0.25)
			(keepout
				(tracks not_allowed)
				(vias allowed)
				(pads allowed)
				(copperpour not_allowed)
				(footprints allowed)
			)
			(placement
				(enabled no)
				(sheetname "")
			)
			(fill
				(thermal_gap 0.5)
				(thermal_bridge_width 0.5)
				(island_removal_mode 0)
			)
			(polygon
				(pts
					(arc
						(start 103.4796 14.534388)
						(mid 101.6254 14.534388)
						(end 103.4796 14.534388)
					)
				)
			)
		)
		(zone
			(layers "F.Cu" "B.Cu" "In1.Cu" "In2.Cu" "In3.Cu" "In4.Cu" "In5.Cu" "In6.Cu"
				"In7.Cu" "In8.Cu" "In9.Cu" "In10.Cu"
			)
			(hatch none 0.5)
			(connect_pads
				(clearance 0)
			)
			(min_thickness 0.25)
			(keepout
				(tracks not_allowed)
				(vias allowed)
				(pads allowed)
				(copperpour not_allowed)
				(footprints allowed)
			)
			(placement
				(enabled no)
				(sheetname "")
			)
			(fill
				(thermal_gap 0.5)
				(thermal_bridge_width 0.5)
				(island_removal_mode 0)
			)
			(polygon
				(pts
					(arc
						(start 103.4796 20.884388)
						(mid 101.6254 20.884388)
						(end 103.4796 20.884388)
					)
				)
			)
		)
		(zone
			(layer "B.Cu")
			(hatch none 0.5)
			(connect_pads
				(clearance 0)
			)
			(min_thickness 0.25)
			(keepout
				(tracks not_allowed)
				(vias allowed)
				(pads allowed)
				(copperpour not_allowed)
				(footprints allowed)
			)
			(placement
				(enabled no)
				(sheetname "")
			)
			(fill
				(thermal_gap 0.5)
				(thermal_bridge_width 0.5)
				(island_removal_mode 0)
			)
			(polygon
				(pts
					(xy 101.83114 16.883888) (xy 101.735636 16.883888) (xy 101.735636 17.480788) (xy 101.329236 17.480788)
					(xy 101.329236 16.883888) (xy 101.235764 16.883888) (xy 101.235764 17.480788) (xy 100.829364 17.480788)
					(xy 100.829364 16.883888) (xy 100.73386 16.883888) (xy 100.73386 17.582388) (xy 101.83114 17.582388)
				)
			)
		)
	)
	(footprint ""
		(layer "B.Cu")
		(at 70.869556 -55.53202)
		(property "Reference" "L6"
			(at 0 0 0)
			(layer "B.SilkS")
			(hide yes)
			(effects
				(font
					(size 1.27 1.27)
				)
				(justify mirror)
			)
		)
		(property "Value" ""
			(at 0 0 0)
			(layer "B.Fab")
			(effects
				(font
					(size 1.27 1.27)
				)
				(justify mirror)
			)
		)
		(duplicate_pad_numbers_are_jumpers no)
		(fp_line
			(start -1.27 0.5842)
			(end -1.27 -0.5842)
			(stroke
				(width 0.1524)
				(type default)
			)
			(layer "B.SilkS")
		)
		(fp_line
			(start -1.27 0.5842)
			(end 1.27 0.5842)
			(stroke
				(width 0.1524)
				(type default)
			)
			(layer "B.SilkS")
		)
		(fp_line
			(start -0.127 0.5842)
			(end -0.127 -0.5842)
			(stroke
				(width 0.1524)
				(type default)
			)
			(layer "B.SilkS")
		)
		(fp_line
			(start 0.127 0.5842)
			(end 0.127 -0.5842)
			(stroke
				(width 0.1524)
				(type default)
			)
			(layer "B.SilkS")
		)
		(fp_line
			(start 1.27 -0.5842)
			(end -1.27 -0.5842)
			(stroke
				(width 0.1524)
				(type default)
			)
			(layer "B.SilkS")
		)
		(fp_line
			(start 1.27 -0.5588)
			(end 1.27 -0.5842)
			(stroke
				(width 0.1524)
				(type default)
			)
			(layer "B.SilkS")
		)
		(fp_line
			(start 1.27 0.5842)
			(end 1.27 -0.5842)
			(stroke
				(width 0.1524)
				(type default)
			)
			(layer "B.SilkS")
		)
		(fp_line
			(start -1.1938 -0.406654)
			(end -1.1938 0.4064)
			(stroke
				(width 0.1)
				(type default)
			)
			(layer "B.Fab")
		)
		(fp_line
			(start -1.1938 0.4064)
			(end -0.9144 0.4064)
			(stroke
				(width 0.1)
				(type default)
			)
			(layer "B.Fab")
		)
		(fp_line
			(start -0.9144 -0.508)
			(end -0.9144 -0.406654)
			(stroke
				(width 0.1)
				(type default)
			)
			(layer "B.Fab")
		)
		(fp_line
			(start -0.9144 -0.406654)
			(end -1.1938 -0.406654)
			(stroke
				(width 0.1)
				(type default)
			)
			(layer "B.Fab")
		)
		(fp_line
			(start -0.9144 0.4064)
			(end -0.9144 0.508)
			(stroke
				(width 0.1)
				(type default)
			)
			(layer "B.Fab")
		)
		(fp_line
			(start -0.9144 0.508)
			(end 0.9144 0.508)
			(stroke
				(width 0.1)
				(type default)
			)
			(layer "B.Fab")
		)
		(fp_line
			(start 0.9144 -0.508)
			(end -0.9144 -0.508)
			(stroke
				(width 0.1)
				(type default)
			)
			(layer "B.Fab")
		)
		(fp_line
			(start 0.9144 -0.406654)
			(end 0.9144 -0.508)
			(stroke
				(width 0.1)
				(type default)
			)
			(layer "B.Fab")
		)
		(fp_line
			(start 0.9144 0.406654)
			(end 1.194308 0.406654)
			(stroke
				(width 0.1)
				(type default)
			)
			(layer "B.Fab")
		)
		(fp_line
			(start 0.9144 0.508)
			(end 0.9144 0.406654)
			(stroke
				(width 0.1)
				(type default)
			)
			(layer "B.Fab")
		)
		(fp_line
			(start 1.194308 -0.406654)
			(end 0.9144 -0.406654)
			(stroke
				(width 0.1)
				(type default)
			)
			(layer "B.Fab")
		)
		(fp_line
			(start 1.194308 0.406654)
			(end 1.194308 -0.406654)
			(stroke
				(width 0.1)
				(type default)
			)
			(layer "B.Fab")
		)
		(pad "1" smd rect
			(at 0.7366 0 270)
			(size 0.7112 0.8128)
			(layers "B.Cu" "B.Mask" "B.Paste")
			(net "P1V0_AUX")
		)
		(pad "2" smd rect
			(at -0.7366 0 270)
			(size 0.7112 0.8128)
			(layers "B.Cu" "B.Mask" "B.Paste")
			(net "P1V0_STBY_RC_VCC10A")
		)
	)
	(footprint ""
		(layer "B.Cu")
		(at 8.001 -112.649)
		(property "Reference" ""
			(at 0 0 0)
			(layer "B.SilkS")
			(hide yes)
			(effects
				(font
					(size 1.27 1.27)
				)
				(justify mirror)
			)
		)
		(property "Value" ""
			(at 0 0 0)
			(layer "B.Fab")
			(effects
				(font
					(size 1.27 1.27)
				)
				(justify mirror)
			)
		)
		(duplicate_pad_numbers_are_jumpers no)
		(pad "1" smd circle
			(at 0 0 180)
			(size 0.9906 0.9906)
			(layers "B.Cu" "B.Mask" "B.Paste")
			(net "Net_598")
		)
		(zone
			(layer "B.Cu")
			(hatch none 0.5)
			(connect_pads
				(clearance 0)
			)
			(min_thickness 0.25)
			(keepout
				(tracks not_allowed)
				(vias allowed)
				(pads allowed)
				(copperpour not_allowed)
				(footprints allowed)
			)
			(placement
				(enabled no)
				(sheetname "")
			)
			(fill
				(thermal_gap 0.5)
				(thermal_bridge_width 0.5)
				(island_removal_mode 0)
			)
			(polygon
				(pts
					(arc
						(start 9.6266 -112.649)
						(mid 6.3754 -112.649)
						(end 9.6266 -112.649)
					)
				)
			)
		)
	)
	(footprint ""
		(layer "B.Cu")
		(at 70.543674 -37.05479 90)
		(property "Reference" "C126"
			(at 0 0 90)
			(layer "B.SilkS")
			(hide yes)
			(effects
				(font
					(size 1.27 1.27)
				)
				(justify mirror)
			)
		)
		(property "Value" ""
			(at 0 0 90)
			(layer "B.Fab")
			(effects
				(font
					(size 1.27 1.27)
				)
				(justify mirror)
			)
		)
		(duplicate_pad_numbers_are_jumpers no)
		(fp_line
			(start 1.2954 -0.5842)
			(end -1.2954 -0.5842)
			(stroke
				(width 0.1524)
				(type default)
			)
			(layer "B.SilkS")
		)
		(fp_line
			(start 0 -0.5842)
			(end 0 0.5842)
			(stroke
				(width 0.1524)
				(type default)
			)
			(layer "B.SilkS")
		)
		(fp_line
			(start -1.2954 -0.5842)
			(end -1.2954 0.5842)
			(stroke
				(width 0.1524)
				(type default)
			)
			(layer "B.SilkS")
		)
		(fp_line
			(start 1.2954 0.5842)
			(end 1.2954 -0.5842)
			(stroke
				(width 0.1524)
				(type default)
			)
			(layer "B.SilkS")
		)
		(fp_line
			(start -1.2954 0.5842)
			(end 1.2954 0.5842)
			(stroke
				(width 0.1524)
				(type default)
			)
			(layer "B.SilkS")
		)
		(fp_line
			(start 0.8636 -0.4572)
			(end -0.8636 -0.4572)
			(stroke
				(width 0.1)
				(type default)
			)
			(layer "B.Fab")
		)
		(fp_line
			(start -0.8636 -0.4572)
			(end -0.8636 -0.4064)
			(stroke
				(width 0.1)
				(type default)
			)
			(layer "B.Fab")
		)
		(fp_line
			(start 1.1938 -0.4064)
			(end 0.8636 -0.4064)
			(stroke
				(width 0.1)
				(type default)
			)
			(layer "B.Fab")
		)
		(fp_line
			(start 0.8636 -0.4064)
			(end 0.8636 -0.4572)
			(stroke
				(width 0.1)
				(type default)
			)
			(layer "B.Fab")
		)
		(fp_line
			(start -0.8636 -0.4064)
			(end -1.1938 -0.4064)
			(stroke
				(width 0.1)
				(type default)
			)
			(layer "B.Fab")
		)
		(fp_line
			(start -1.1938 -0.4064)
			(end -1.1938 0.4064)
			(stroke
				(width 0.1)
				(type default)
			)
			(layer "B.Fab")
		)
		(fp_line
			(start 1.1938 0.4064)
			(end 1.1938 -0.4064)
			(stroke
				(width 0.1)
				(type default)
			)
			(layer "B.Fab")
		)
		(fp_line
			(start 0.8636 0.4064)
			(end 1.1938 0.4064)
			(stroke
				(width 0.1)
				(type default)
			)
			(layer "B.Fab")
		)
		(fp_line
			(start -0.8636 0.4064)
			(end -0.8636 0.4572)
			(stroke
				(width 0.1)
				(type default)
			)
			(layer "B.Fab")
		)
		(fp_line
			(start -1.1938 0.4064)
			(end -0.8636 0.4064)
			(stroke
				(width 0.1)
				(type default)
			)
			(layer "B.Fab")
		)
		(fp_line
			(start 0.8636 0.4572)
			(end 0.8636 0.4064)
			(stroke
				(width 0.1)
				(type default)
			)
			(layer "B.Fab")
		)
		(fp_line
			(start -0.8636 0.4572)
			(end 0.8636 0.4572)
			(stroke
				(width 0.1)
				(type default)
			)
			(layer "B.Fab")
		)
		(pad "1" smd rect
			(at 0.7366 0)
			(size 0.7112 0.8128)
			(layers "B.Cu" "B.Mask" "B.Paste")
			(net "P1V8_AUX")
		)
		(pad "2" smd rect
			(at -0.7366 0)
			(size 0.7112 0.8128)
			(layers "B.Cu" "B.Mask" "B.Paste")
			(net "GND")
		)
	)
	(footprint ""
		(layer "B.Cu")
		(at 60.722256 -53.533548 -90)
		(property "Reference" "C21"
			(at 0 0 90)
			(layer "B.SilkS")
			(hide yes)
			(effects
				(font
					(size 1.27 1.27)
				)
				(justify mirror)
			)
		)
		(property "Value" ""
			(at 0 0 90)
			(layer "B.Fab")
			(effects
				(font
					(size 1.27 1.27)
				)
				(justify mirror)
			)
		)
		(duplicate_pad_numbers_are_jumpers no)
		(fp_line
			(start -0.7874 0.4064)
			(end 0.7874 0.4064)
			(stroke
				(width 0.1524)
				(type default)
			)
			(layer "B.SilkS")
		)
		(fp_line
			(start 0.7874 0.4064)
			(end 0.7874 -0.4064)
			(stroke
				(width 0.1524)
				(type default)
			)
			(layer "B.SilkS")
		)
		(fp_line
			(start -0.7874 -0.4064)
			(end -0.7874 0.4064)
			(stroke
				(width 0.1524)
				(type default)
			)
			(layer "B.SilkS")
		)
		(fp_line
			(start 0.7874 -0.4064)
			(end -0.7874 -0.4064)
			(stroke
				(width 0.1524)
				(type default)
			)
			(layer "B.SilkS")
		)
		(fp_line
			(start -0.67945 0.3048)
			(end -0.120396 0.3048)
			(stroke
				(width 0.1)
				(type default)
			)
			(layer "B.Fab")
		)
		(fp_line
			(start -0.120396 0.3048)
			(end -0.120396 0.2794)
			(stroke
				(width 0.1)
				(type default)
			)
			(layer "B.Fab")
		)
		(fp_line
			(start 0.12065 0.3048)
			(end 0.67945 0.3048)
			(stroke
				(width 0.1)
				(type default)
			)
			(layer "B.Fab")
		)
		(fp_line
			(start 0.67945 0.3048)
			(end 0.67945 -0.305054)
			(stroke
				(width 0.1)
				(type default)
			)
			(layer "B.Fab")
		)
		(fp_line
			(start -0.120396 0.2794)
			(end 0.12065 0.2794)
			(stroke
				(width 0.1)
				(type default)
			)
			(layer "B.Fab")
		)
		(fp_line
			(start 0.12065 0.2794)
			(end 0.12065 0.3048)
			(stroke
				(width 0.1)
				(type default)
			)
			(layer "B.Fab")
		)
		(fp_line
			(start -0.12065 -0.2794)
			(end -0.12065 -0.3048)
			(stroke
				(width 0.1)
				(type default)
			)
			(layer "B.Fab")
		)
		(fp_line
			(start 0.12065 -0.2794)
			(end -0.12065 -0.2794)
			(stroke
				(width 0.1)
				(type default)
			)
			(layer "B.Fab")
		)
		(fp_line
			(start -0.67945 -0.3048)
			(end -0.67945 0.3048)
			(stroke
				(width 0.1)
				(type default)
			)
			(layer "B.Fab")
		)
		(fp_line
			(start -0.12065 -0.3048)
			(end -0.67945 -0.3048)
			(stroke
				(width 0.1)
				(type default)
			)
			(layer "B.Fab")
		)
		(fp_line
			(start 0.12065 -0.305054)
			(end 0.12065 -0.2794)
			(stroke
				(width 0.1)
				(type default)
			)
			(layer "B.Fab")
		)
		(fp_line
			(start 0.67945 -0.305054)
			(end 0.12065 -0.305054)
			(stroke
				(width 0.1)
				(type default)
			)
			(layer "B.Fab")
		)
		(pad "1" smd circle
			(at 0.40005 0 90)
			(size 0 0)
			(layers "B.Cu" "B.Mask" "B.Paste")
			(net "P0V6_DDR_VREF_AUX")
		)
		(pad "2" smd circle
			(at -0.40005 0 90)
			(size 0 0)
			(layers "B.Cu" "B.Mask" "B.Paste")
			(net "GND")
		)
	)
	(footprint ""
		(layer "B.Cu")
		(at 69.997828 -30.8356 180)
		(property "Reference" "C240"
			(at 0 0 0)
			(layer "B.SilkS")
			(hide yes)
			(effects
				(font
					(size 1.27 1.27)
				)
				(justify mirror)
			)
		)
		(property "Value" ""
			(at 0 0 0)
			(layer "B.Fab")
			(effects
				(font
					(size 1.27 1.27)
				)
				(justify mirror)
			)
		)
		(duplicate_pad_numbers_are_jumpers no)
		(fp_line
			(start 0.7874 0.4064)
			(end 0.7874 -0.4064)
			(stroke
				(width 0.1524)
				(type default)
			)
			(layer "B.SilkS")
		)
		(fp_line
			(start 0.7874 -0.4064)
			(end -0.7874 -0.4064)
			(stroke
				(width 0.1524)
				(type default)
			)
			(layer "B.SilkS")
		)
		(fp_line
			(start -0.7874 0.4064)
			(end 0.7874 0.4064)
			(stroke
				(width 0.1524)
				(type default)
			)
			(layer "B.SilkS")
		)
		(fp_line
			(start -0.7874 -0.4064)
			(end -0.7874 0.4064)
			(stroke
				(width 0.1524)
				(type default)
			)
			(layer "B.SilkS")
		)
		(fp_line
			(start 0.67945 0.3048)
			(end 0.67945 -0.305054)
			(stroke
				(width 0.1)
				(type default)
			)
			(layer "B.Fab")
		)
		(fp_line
			(start 0.67945 -0.305054)
			(end 0.12065 -0.305054)
			(stroke
				(width 0.1)
				(type default)
			)
			(layer "B.Fab")
		)
		(fp_line
			(start 0.12065 0.3048)
			(end 0.67945 0.3048)
			(stroke
				(width 0.1)
				(type default)
			)
			(layer "B.Fab")
		)
		(fp_line
			(start 0.12065 0.2794)
			(end 0.12065 0.3048)
			(stroke
				(width 0.1)
				(type default)
			)
			(layer "B.Fab")
		)
		(fp_line
			(start 0.12065 -0.2794)
			(end -0.12065 -0.2794)
			(stroke
				(width 0.1)
				(type default)
			)
			(layer "B.Fab")
		)
		(fp_line
			(start 0.12065 -0.305054)
			(end 0.12065 -0.2794)
			(stroke
				(width 0.1)
				(type default)
			)
			(layer "B.Fab")
		)
		(fp_line
			(start -0.120396 0.3048)
			(end -0.120396 0.2794)
			(stroke
				(width 0.1)
				(type default)
			)
			(layer "B.Fab")
		)
		(fp_line
			(start -0.120396 0.2794)
			(end 0.12065 0.2794)
			(stroke
				(width 0.1)
				(type default)
			)
			(layer "B.Fab")
		)
		(fp_line
			(start -0.12065 -0.2794)
			(end -0.12065 -0.3048)
			(stroke
				(width 0.1)
				(type default)
			)
			(layer "B.Fab")
		)
		(fp_line
			(start -0.12065 -0.3048)
			(end -0.67945 -0.3048)
			(stroke
				(width 0.1)
				(type default)
			)
			(layer "B.Fab")
		)
		(fp_line
			(start -0.67945 0.3048)
			(end -0.120396 0.3048)
			(stroke
				(width 0.1)
				(type default)
			)
			(layer "B.Fab")
		)
		(fp_line
			(start -0.67945 -0.3048)
			(end -0.67945 0.3048)
			(stroke
				(width 0.1)
				(type default)
			)
			(layer "B.Fab")
		)
		(pad "1" smd circle
			(at 0.40005 0)
			(size 0 0)
			(layers "B.Cu" "B.Mask" "B.Paste")
			(net "P3V3_AUX")
		)
		(pad "2" smd circle
			(at -0.40005 0)
			(size 0 0)
			(layers "B.Cu" "B.Mask" "B.Paste")
			(net "GND")
		)
	)
)
